(kicad_pcb
	(version 20260206)
	(generator "pcbnew")
	(generator_version "10.0")
	(general
		(thickness 1.6)
		(legacy_teardrops no)
	)
	(paper "A4")
	(title_block
		(title "01162023_DA0F0TEBIF0_F0T_Expander_BD_F_brd_V02_OCP.brd")
		(comment 1 "Grand Teton / footprints 3463-3469 of 9728")
	)
	(layers
		(0 "F.Cu" signal "TOP")
		(4 "In1.Cu" signal "GND")
		(6 "In2.Cu" signal "VCC")
		(8 "In3.Cu" signal "VCC1")
		(10 "In4.Cu" signal "GND1")
		(12 "In5.Cu" signal "IN1")
		(14 "In6.Cu" signal "GND2")
		(16 "In7.Cu" signal "IN2")
		(18 "In8.Cu" signal "GND3")
		(20 "In9.Cu" signal "IN3")
		(22 "In10.Cu" signal "GND4")
		(24 "In11.Cu" signal "IN4")
		(26 "In12.Cu" signal "GND5")
		(28 "In13.Cu" signal "IN5")
		(30 "In14.Cu" signal "GND6")
		(32 "In15.Cu" signal "IN6")
		(34 "In16.Cu" signal "GND7")
		(2 "B.Cu" signal "BOTTOM")
		(9 "F.Adhes" user "F.Adhesive")
		(11 "B.Adhes" user "B.Adhesive")
		(13 "F.Paste" user "Package Geometry/Pastemask Top")
		(15 "B.Paste" user "Package Geometry/Pastemask Bottom")
		(5 "F.SilkS" user "Ref Des/Silkscreen Top")
		(7 "B.SilkS" user "Ref Des/Silkscreen Bottom")
		(1 "F.Mask" user "Board Geometry/Soldermask Top")
		(3 "B.Mask" user "Board Geometry/Soldermask Bottom")
		(17 "Dwgs.User" user "User.Drawings")
		(19 "Cmts.User" user "User.Comments")
		(21 "Eco1.User" user "User.Eco1")
		(23 "Eco2.User" user "User.Eco2")
		(25 "Edge.Cuts" user "Board Geometry/Outline")
		(27 "Margin" user)
		(31 "F.CrtYd" user "Package Geometry/Place Bound Top")
		(29 "B.CrtYd" user "Package Geometry/Place Bound Bottom")
		(35 "F.Fab" user "Ref Des/Assembly Top")
		(33 "B.Fab" user "Ref Des/Assembly Bottom")
	)
	(footprint ""
		(layer "F.Cu")
		(at 29.548328 -343.952322 90)
		(property "Reference" "C184"
			(at 0 0 90)
			(layer "F.SilkS")
			(hide yes)
			(effects
				(font
					(size 1.27 1.27)
				)
			)
		)
		(property "Value" ""
			(at 0 0 90)
			(layer "F.Fab")
			(effects
				(font
					(size 1.27 1.27)
				)
			)
		)
		(duplicate_pad_numbers_are_jumpers no)
		(fp_line
			(start 0.299974 -0.150114)
			(end 0.299974 0.150114)
			(stroke
				(width 0.1)
				(type default)
			)
			(layer "F.Fab")
		)
		(fp_line
			(start -0.299974 -0.150114)
			(end 0.299974 -0.150114)
			(stroke
				(width 0.1)
				(type default)
			)
			(layer "F.Fab")
		)
		(fp_line
			(start 0.299974 0.150114)
			(end -0.299974 0.150114)
			(stroke
				(width 0.1)
				(type default)
			)
			(layer "F.Fab")
		)
		(fp_line
			(start -0.299974 0.150114)
			(end -0.299974 -0.150114)
			(stroke
				(width 0.1)
				(type default)
			)
			(layer "F.Fab")
		)
		(pad "1" smd rect
			(at -0.2667 0 90)
			(size 0.3048 0.381)
			(layers "F.Cu" "F.Mask" "F.Paste")
			(net "P5E_PEX0_STN7_TX_DN<116>")
		)
		(pad "2" smd rect
			(at 0.2667 0 90)
			(size 0.3048 0.381)
			(layers "F.Cu" "F.Mask" "F.Paste")
			(net "P5E_PEX0_STN7_TX_C_DN<116>")
		)
	)
	(footprint ""
		(layer "F.Cu")
		(at 428.923704 -87.349076 -90)
		(property "Reference" "R403"
			(at 0 0 270)
			(layer "F.SilkS")
			(hide yes)
			(effects
				(font
					(size 1.27 1.27)
				)
			)
		)
		(property "Value" ""
			(at 0 0 270)
			(layer "F.Fab")
			(effects
				(font
					(size 1.27 1.27)
				)
			)
		)
		(duplicate_pad_numbers_are_jumpers no)
		(fp_line
			(start -0.7874 0.4064)
			(end -0.7874 -0.4064)
			(stroke
				(width 0.1524)
				(type default)
			)
			(layer "F.SilkS")
		)
		(fp_line
			(start 0.7874 0.4064)
			(end -0.7874 0.4064)
			(stroke
				(width 0.1524)
				(type default)
			)
			(layer "F.SilkS")
		)
		(fp_line
			(start -0.7874 -0.4064)
			(end 0.7874 -0.4064)
			(stroke
				(width 0.1524)
				(type default)
			)
			(layer "F.SilkS")
		)
		(fp_line
			(start 0.7874 -0.4064)
			(end 0.7874 0.4064)
			(stroke
				(width 0.1524)
				(type default)
			)
			(layer "F.SilkS")
		)
		(fp_line
			(start -0.67945 0.3048)
			(end -0.67945 -0.305054)
			(stroke
				(width 0.1)
				(type default)
			)
			(layer "F.Fab")
		)
		(fp_line
			(start -0.12065 0.3048)
			(end -0.67945 0.3048)
			(stroke
				(width 0.1)
				(type default)
			)
			(layer "F.Fab")
		)
		(fp_line
			(start 0.120396 0.3048)
			(end 0.120396 0.2794)
			(stroke
				(width 0.1)
				(type default)
			)
			(layer "F.Fab")
		)
		(fp_line
			(start 0.67945 0.3048)
			(end 0.120396 0.3048)
			(stroke
				(width 0.1)
				(type default)
			)
			(layer "F.Fab")
		)
		(fp_line
			(start -0.12065 0.2794)
			(end -0.12065 0.3048)
			(stroke
				(width 0.1)
				(type default)
			)
			(layer "F.Fab")
		)
		(fp_line
			(start 0.120396 0.2794)
			(end -0.12065 0.2794)
			(stroke
				(width 0.1)
				(type default)
			)
			(layer "F.Fab")
		)
		(fp_line
			(start -0.12065 -0.2794)
			(end 0.12065 -0.2794)
			(stroke
				(width 0.1)
				(type default)
			)
			(layer "F.Fab")
		)
		(fp_line
			(start 0.12065 -0.2794)
			(end 0.12065 -0.3048)
			(stroke
				(width 0.1)
				(type default)
			)
			(layer "F.Fab")
		)
		(fp_line
			(start 0.12065 -0.3048)
			(end 0.67945 -0.3048)
			(stroke
				(width 0.1)
				(type default)
			)
			(layer "F.Fab")
		)
		(fp_line
			(start 0.67945 -0.3048)
			(end 0.67945 0.3048)
			(stroke
				(width 0.1)
				(type default)
			)
			(layer "F.Fab")
		)
		(fp_line
			(start -0.67945 -0.305054)
			(end -0.12065 -0.305054)
			(stroke
				(width 0.1)
				(type default)
			)
			(layer "F.Fab")
		)
		(fp_line
			(start -0.12065 -0.305054)
			(end -0.12065 -0.2794)
			(stroke
				(width 0.1)
				(type default)
			)
			(layer "F.Fab")
		)
		(pad "1" smd circle
			(at -0.40005 0 270)
			(size 0 0)
			(layers "F.Cu" "F.Mask" "F.Paste")
			(net "RST_NIC7_PERST1_R_N")
		)
		(pad "2" smd circle
			(at 0.40005 0 270)
			(size 0 0)
			(layers "F.Cu" "F.Mask" "F.Paste")
			(net "RST_HP_NIC7_BUF_N")
		)
	)
	(footprint ""
		(layer "F.Cu")
		(at 138.985244 -88.956642 180)
		(property "Reference" "R1563"
			(at 0 0 180)
			(layer "F.SilkS")
			(hide yes)
			(effects
				(font
					(size 1.27 1.27)
				)
			)
		)
		(property "Value" ""
			(at 0 0 180)
			(layer "F.Fab")
			(effects
				(font
					(size 1.27 1.27)
				)
			)
		)
		(duplicate_pad_numbers_are_jumpers no)
		(fp_line
			(start 0.7874 0.4064)
			(end -0.7874 0.4064)
			(stroke
				(width 0.1524)
				(type default)
			)
			(layer "F.SilkS")
		)
		(fp_line
			(start 0.7874 -0.4064)
			(end 0.7874 0.4064)
			(stroke
				(width 0.1524)
				(type default)
			)
			(layer "F.SilkS")
		)
		(fp_line
			(start -0.7874 0.4064)
			(end -0.7874 -0.4064)
			(stroke
				(width 0.1524)
				(type default)
			)
			(layer "F.SilkS")
		)
		(fp_line
			(start -0.7874 -0.4064)
			(end 0.7874 -0.4064)
			(stroke
				(width 0.1524)
				(type default)
			)
			(layer "F.SilkS")
		)
		(fp_line
			(start 0.67945 0.3048)
			(end 0.120396 0.3048)
			(stroke
				(width 0.1)
				(type default)
			)
			(layer "F.Fab")
		)
		(fp_line
			(start 0.67945 -0.3048)
			(end 0.67945 0.3048)
			(stroke
				(width 0.1)
				(type default)
			)
			(layer "F.Fab")
		)
		(fp_line
			(start 0.12065 -0.2794)
			(end 0.12065 -0.3048)
			(stroke
				(width 0.1)
				(type default)
			)
			(layer "F.Fab")
		)
		(fp_line
			(start 0.12065 -0.3048)
			(end 0.67945 -0.3048)
			(stroke
				(width 0.1)
				(type default)
			)
			(layer "F.Fab")
		)
		(fp_line
			(start 0.120396 0.3048)
			(end 0.120396 0.2794)
			(stroke
				(width 0.1)
				(type default)
			)
			(layer "F.Fab")
		)
		(fp_line
			(start 0.120396 0.2794)
			(end -0.12065 0.2794)
			(stroke
				(width 0.1)
				(type default)
			)
			(layer "F.Fab")
		)
		(fp_line
			(start -0.12065 0.3048)
			(end -0.67945 0.3048)
			(stroke
				(width 0.1)
				(type default)
			)
			(layer "F.Fab")
		)
		(fp_line
			(start -0.12065 0.2794)
			(end -0.12065 0.3048)
			(stroke
				(width 0.1)
				(type default)
			)
			(layer "F.Fab")
		)
		(fp_line
			(start -0.12065 -0.2794)
			(end 0.12065 -0.2794)
			(stroke
				(width 0.1)
				(type default)
			)
			(layer "F.Fab")
		)
		(fp_line
			(start -0.12065 -0.305054)
			(end -0.12065 -0.2794)
			(stroke
				(width 0.1)
				(type default)
			)
			(layer "F.Fab")
		)
		(fp_line
			(start -0.67945 0.3048)
			(end -0.67945 -0.305054)
			(stroke
				(width 0.1)
				(type default)
			)
			(layer "F.Fab")
		)
		(fp_line
			(start -0.67945 -0.305054)
			(end -0.12065 -0.305054)
			(stroke
				(width 0.1)
				(type default)
			)
			(layer "F.Fab")
		)
		(pad "1" smd circle
			(at -0.40005 0 180)
			(size 0 0)
			(layers "F.Cu" "F.Mask" "F.Paste")
			(net "P3V3_AUX")
		)
		(pad "2" smd circle
			(at 0.40005 0 180)
			(size 0 0)
			(layers "F.Cu" "F.Mask" "F.Paste")
			(net "SMB_BIC_I2C9_MUX0_SSD4_R_SCL")
		)
	)
	(footprint ""
		(layer "F.Cu")
		(at 336.042 -169.037)
		(property "Reference" "R4732"
			(at 0 0 0)
			(layer "F.SilkS")
			(hide yes)
			(effects
				(font
					(size 1.27 1.27)
				)
			)
		)
		(property "Value" ""
			(at 0 0 0)
			(layer "F.Fab")
			(effects
				(font
					(size 1.27 1.27)
				)
			)
		)
		(duplicate_pad_numbers_are_jumpers no)
		(fp_line
			(start -0.7874 -0.4064)
			(end 0.7874 -0.4064)
			(stroke
				(width 0.1524)
				(type default)
			)
			(layer "F.SilkS")
		)
		(fp_line
			(start -0.7874 0.4064)
			(end -0.7874 -0.4064)
			(stroke
				(width 0.1524)
				(type default)
			)
			(layer "F.SilkS")
		)
		(fp_line
			(start 0.7874 -0.4064)
			(end 0.7874 0.4064)
			(stroke
				(width 0.1524)
				(type default)
			)
			(layer "F.SilkS")
		)
		(fp_line
			(start 0.7874 0.4064)
			(end -0.7874 0.4064)
			(stroke
				(width 0.1524)
				(type default)
			)
			(layer "F.SilkS")
		)
		(fp_line
			(start -0.67945 -0.305054)
			(end -0.12065 -0.305054)
			(stroke
				(width 0.1)
				(type default)
			)
			(layer "F.Fab")
		)
		(fp_line
			(start -0.67945 0.3048)
			(end -0.67945 -0.305054)
			(stroke
				(width 0.1)
				(type default)
			)
			(layer "F.Fab")
		)
		(fp_line
			(start -0.12065 -0.305054)
			(end -0.12065 -0.2794)
			(stroke
				(width 0.1)
				(type default)
			)
			(layer "F.Fab")
		)
		(fp_line
			(start -0.12065 -0.2794)
			(end 0.12065 -0.2794)
			(stroke
				(width 0.1)
				(type default)
			)
			(layer "F.Fab")
		)
		(fp_line
			(start -0.12065 0.2794)
			(end -0.12065 0.3048)
			(stroke
				(width 0.1)
				(type default)
			)
			(layer "F.Fab")
		)
		(fp_line
			(start -0.12065 0.3048)
			(end -0.67945 0.3048)
			(stroke
				(width 0.1)
				(type default)
			)
			(layer "F.Fab")
		)
		(fp_line
			(start 0.120396 0.2794)
			(end -0.12065 0.2794)
			(stroke
				(width 0.1)
				(type default)
			)
			(layer "F.Fab")
		)
		(fp_line
			(start 0.120396 0.3048)
			(end 0.120396 0.2794)
			(stroke
				(width 0.1)
				(type default)
			)
			(layer "F.Fab")
		)
		(fp_line
			(start 0.12065 -0.3048)
			(end 0.67945 -0.3048)
			(stroke
				(width 0.1)
				(type default)
			)
			(layer "F.Fab")
		)
		(fp_line
			(start 0.12065 -0.2794)
			(end 0.12065 -0.3048)
			(stroke
				(width 0.1)
				(type default)
			)
			(layer "F.Fab")
		)
		(fp_line
			(start 0.67945 -0.3048)
			(end 0.67945 0.3048)
			(stroke
				(width 0.1)
				(type default)
			)
			(layer "F.Fab")
		)
		(fp_line
			(start 0.67945 0.3048)
			(end 0.120396 0.3048)
			(stroke
				(width 0.1)
				(type default)
			)
			(layer "F.Fab")
		)
		(pad "1" smd circle
			(at -0.40005 0)
			(size 0 0)
			(layers "F.Cu" "F.Mask" "F.Paste")
			(net "P3V3_AUX")
		)
		(pad "2" smd circle
			(at 0.40005 0)
			(size 0 0)
			(layers "F.Cu" "F.Mask" "F.Paste")
			(net "RST_PEX_SSD10_PERST_R_N")
		)
	)
	(footprint ""
		(layer "F.Cu")
		(at 13.221716 -129.799334 180)
		(property "Reference" "PD24"
			(at 7.532116 -0.311404 0)
			(unlocked yes)
			(layer "F.SilkS")
			(effects
				(font
					(size 0.7874 0.5842)
					(thickness 0.1524)
				)
				(justify left)
			)
		)
		(property "Value" ""
			(at 0 0 180)
			(layer "F.Fab")
			(effects
				(font
					(size 1.27 1.27)
				)
			)
		)
		(duplicate_pad_numbers_are_jumpers no)
		(fp_line
			(start 4.240784 1.970024)
			(end 4.240784 -1.970024)
			(stroke
				(width 0.1524)
				(type default)
			)
			(layer "F.SilkS")
		)
		(fp_line
			(start 4.240784 -1.970024)
			(end -3.656584 -1.970024)
			(stroke
				(width 0.1524)
				(type default)
			)
			(layer "F.SilkS")
		)
		(fp_line
			(start -3.656584 1.970024)
			(end 4.240784 1.970024)
			(stroke
				(width 0.1524)
				(type default)
			)
			(layer "F.SilkS")
		)
		(fp_line
			(start -3.656584 -1.970024)
			(end -3.656584 1.970024)
			(stroke
				(width 0.1524)
				(type default)
			)
			(layer "F.SilkS")
		)
		(fp_poly
			(pts
				(xy 3.580384 1.970024) (xy 3.580384 -1.970024) (xy 4.240784 -1.970024) (xy 4.240784 1.970024)
			)
			(stroke
				(width 0)
				(type default)
			)
			(fill yes)
			(layer "F.SilkS")
		)
		(fp_line
			(start 2.3749 1.970024)
			(end 2.3749 -1.970024)
			(stroke
				(width 0.1)
				(type default)
			)
			(layer "F.Fab")
		)
		(fp_line
			(start 2.3749 -1.970024)
			(end -2.3749 -1.970024)
			(stroke
				(width 0.1)
				(type default)
			)
			(layer "F.Fab")
		)
		(fp_line
			(start -2.3749 1.970024)
			(end 2.3749 1.970024)
			(stroke
				(width 0.1)
				(type default)
			)
			(layer "F.Fab")
		)
		(fp_line
			(start -2.3749 -1.970024)
			(end -2.3749 1.970024)
			(stroke
				(width 0.1)
				(type default)
			)
			(layer "F.Fab")
		)
		(fp_text user "-"
			(at 4.1656 -0.23495 180)
			(unlocked yes)
			(layer "F.Fab")
			(effects
				(font
					(size 1.905 1.4224)
					(thickness 0.1524)
				)
				(justify left)
			)
		)
		(fp_text user "+"
			(at -4.9784 -0.23495 180)
			(unlocked yes)
			(layer "F.Fab")
			(effects
				(font
					(size 1.905 1.4224)
					(thickness 0.1524)
				)
				(justify left)
			)
		)
		(pad "A" smd rect
			(at -2.450084 0 180)
			(size 2.159 2.2606)
			(layers "F.Cu" "F.Mask" "F.Paste")
			(net "GND")
		)
		(pad "C" smd rect
			(at 2.450084 0 180)
			(size 2.159 2.2606)
			(layers "F.Cu" "F.Mask" "F.Paste")
			(net "P12V_AUX")
		)
	)
	(footprint ""
		(layer "F.Cu")
		(at 63.6778 -114.267742)
		(property "Reference" "R89"
			(at 0 0 0)
			(layer "F.SilkS")
			(hide yes)
			(effects
				(font
					(size 1.27 1.27)
				)
			)
		)
		(property "Value" ""
			(at 0 0 0)
			(layer "F.Fab")
			(effects
				(font
					(size 1.27 1.27)
				)
			)
		)
		(duplicate_pad_numbers_are_jumpers no)
		(fp_line
			(start -0.7874 -0.4064)
			(end 0.7874 -0.4064)
			(stroke
				(width 0.1524)
				(type default)
			)
			(layer "F.SilkS")
		)
		(fp_line
			(start -0.7874 0.4064)
			(end -0.7874 -0.4064)
			(stroke
				(width 0.1524)
				(type default)
			)
			(layer "F.SilkS")
		)
		(fp_line
			(start 0.7874 -0.4064)
			(end 0.7874 0.4064)
			(stroke
				(width 0.1524)
				(type default)
			)
			(layer "F.SilkS")
		)
		(fp_line
			(start 0.7874 0.4064)
			(end -0.7874 0.4064)
			(stroke
				(width 0.1524)
				(type default)
			)
			(layer "F.SilkS")
		)
		(fp_line
			(start -0.67945 -0.305054)
			(end -0.12065 -0.305054)
			(stroke
				(width 0.1)
				(type default)
			)
			(layer "F.Fab")
		)
		(fp_line
			(start -0.67945 0.3048)
			(end -0.67945 -0.305054)
			(stroke
				(width 0.1)
				(type default)
			)
			(layer "F.Fab")
		)
		(fp_line
			(start -0.12065 -0.305054)
			(end -0.12065 -0.2794)
			(stroke
				(width 0.1)
				(type default)
			)
			(layer "F.Fab")
		)
		(fp_line
			(start -0.12065 -0.2794)
			(end 0.12065 -0.2794)
			(stroke
				(width 0.1)
				(type default)
			)
			(layer "F.Fab")
		)
		(fp_line
			(start -0.12065 0.2794)
			(end -0.12065 0.3048)
			(stroke
				(width 0.1)
				(type default)
			)
			(layer "F.Fab")
		)
		(fp_line
			(start -0.12065 0.3048)
			(end -0.67945 0.3048)
			(stroke
				(width 0.1)
				(type default)
			)
			(layer "F.Fab")
		)
		(fp_line
			(start 0.120396 0.2794)
			(end -0.12065 0.2794)
			(stroke
				(width 0.1)
				(type default)
			)
			(layer "F.Fab")
		)
		(fp_line
			(start 0.120396 0.3048)
			(end 0.120396 0.2794)
			(stroke
				(width 0.1)
				(type default)
			)
			(layer "F.Fab")
		)
		(fp_line
			(start 0.12065 -0.3048)
			(end 0.67945 -0.3048)
			(stroke
				(width 0.1)
				(type default)
			)
			(layer "F.Fab")
		)
		(fp_line
			(start 0.12065 -0.2794)
			(end 0.12065 -0.3048)
			(stroke
				(width 0.1)
				(type default)
			)
			(layer "F.Fab")
		)
		(fp_line
			(start 0.67945 -0.3048)
			(end 0.67945 0.3048)
			(stroke
				(width 0.1)
				(type default)
			)
			(layer "F.Fab")
		)
		(fp_line
			(start 0.67945 0.3048)
			(end 0.120396 0.3048)
			(stroke
				(width 0.1)
				(type default)
			)
			(layer "F.Fab")
		)
		(pad "1" smd circle
			(at -0.40005 0)
			(size 0 0)
			(layers "F.Cu" "F.Mask" "F.Paste")
			(net "RST_SMB_NIC1_MUX_ISO_N")
		)
		(pad "2" smd circle
			(at 0.40005 0)
			(size 0 0)
			(layers "F.Cu" "F.Mask" "F.Paste")
			(net "GND")
		)
	)
	(footprint ""
		(layer "F.Cu")
		(at 242.593368 -318.648588 -90)
		(property "Reference" "PL21"
			(at 0 0 270)
			(layer "F.SilkS")
			(hide yes)
			(effects
				(font
					(size 1.27 1.27)
				)
			)
		)
		(property "Value" ""
			(at 0 0 270)
			(layer "F.Fab")
			(effects
				(font
					(size 1.27 1.27)
				)
			)
		)
		(duplicate_pad_numbers_are_jumpers no)
		(fp_line
			(start -1.27 0.5842)
			(end -1.27 -0.5842)
			(stroke
				(width 0.1524)
				(type default)
			)
			(layer "F.SilkS")
		)
		(fp_line
			(start 1.27 0.5842)
			(end -1.27 0.5842)
			(stroke
				(width 0.1524)
				(type default)
			)
			(layer "F.SilkS")
		)
		(fp_line
			(start 1.27 0.5842)
			(end 1.27 -0.5842)
			(stroke
				(width 0.1524)
				(type default)
			)
			(layer "F.SilkS")
		)
		(fp_line
			(start -1.27 -0.5588)
			(end -1.27 -0.5842)
			(stroke
				(width 0.1524)
				(type default)
			)
			(layer "F.SilkS")
		)
		(fp_line
			(start -1.27 -0.5842)
			(end 1.27 -0.5842)
			(stroke
				(width 0.1524)
				(type default)
			)
			(layer "F.SilkS")
		)
		(fp_line
			(start -0.9144 0.508)
			(end -0.9144 0.406654)
			(stroke
				(width 0.1)
				(type default)
			)
			(layer "F.Fab")
		)
		(fp_line
			(start 0.9144 0.508)
			(end -0.9144 0.508)
			(stroke
				(width 0.1)
				(type default)
			)
			(layer "F.Fab")
		)
		(fp_line
			(start -1.194308 0.406654)
			(end -1.194308 -0.406654)
			(stroke
				(width 0.1)
				(type default)
			)
			(layer "F.Fab")
		)
		(fp_line
			(start -0.9144 0.406654)
			(end -1.194308 0.406654)
			(stroke
				(width 0.1)
				(type default)
			)
			(layer "F.Fab")
		)
		(fp_line
			(start 0.9144 0.4064)
			(end 0.9144 0.508)
			(stroke
				(width 0.1)
				(type default)
			)
			(layer "F.Fab")
		)
		(fp_line
			(start 1.1938 0.4064)
			(end 0.9144 0.4064)
			(stroke
				(width 0.1)
				(type default)
			)
			(layer "F.Fab")
		)
		(fp_line
			(start -1.194308 -0.406654)
			(end -0.9144 -0.406654)
			(stroke
				(width 0.1)
				(type default)
			)
			(layer "F.Fab")
		)
		(fp_line
			(start -0.9144 -0.406654)
			(end -0.9144 -0.508)
			(stroke
				(width 0.1)
				(type default)
			)
			(layer "F.Fab")
		)
		(fp_line
			(start 0.9144 -0.406654)
			(end 1.1938 -0.406654)
			(stroke
				(width 0.1)
				(type default)
			)
			(layer "F.Fab")
		)
		(fp_line
			(start 1.1938 -0.406654)
			(end 1.1938 0.4064)
			(stroke
				(width 0.1)
				(type default)
			)
			(layer "F.Fab")
		)
		(fp_line
			(start -0.9144 -0.508)
			(end 0.9144 -0.508)
			(stroke
				(width 0.1)
				(type default)
			)
			(layer "F.Fab")
		)
		(fp_line
			(start 0.9144 -0.508)
			(end 0.9144 -0.406654)
			(stroke
				(width 0.1)
				(type default)
			)
			(layer "F.Fab")
		)
		(pad "1" smd rect
			(at -0.7366 0 180)
			(size 0.7112 0.8128)
			(layers "F.Cu" "F.Mask" "F.Paste")
			(net "P12V_AUX")
		)
		(pad "2" smd rect
			(at 0.7366 0 180)
			(size 0.7112 0.8128)
			(layers "F.Cu" "F.Mask" "F.Paste")
			(net "SW_P12V_P1V25_PEX2_FLT")
		)
	)
)
